(kicad_pcb
	(version 20260206)
	(generator "pcbnew")
	(generator_version "10.0")
	(general
		(thickness 1.6)
		(legacy_teardrops no)
	)
	(paper "A4")
	(title_block
		(title "01162023_DA0F0TEBIF0_F0T_Expander_BD_F_brd_V02_OCP.brd")
		(comment 1 "Grand Teton / footprints 605-610 of 9728")
	)
	(layers
		(0 "F.Cu" signal "TOP")
		(4 "In1.Cu" signal "GND")
		(6 "In2.Cu" signal "VCC")
		(8 "In3.Cu" signal "VCC1")
		(10 "In4.Cu" signal "GND1")
		(12 "In5.Cu" signal "IN1")
		(14 "In6.Cu" signal "GND2")
		(16 "In7.Cu" signal "IN2")
		(18 "In8.Cu" signal "GND3")
		(20 "In9.Cu" signal "IN3")
		(22 "In10.Cu" signal "GND4")
		(24 "In11.Cu" signal "IN4")
		(26 "In12.Cu" signal "GND5")
		(28 "In13.Cu" signal "IN5")
		(30 "In14.Cu" signal "GND6")
		(32 "In15.Cu" signal "IN6")
		(34 "In16.Cu" signal "GND7")
		(2 "B.Cu" signal "BOTTOM")
		(9 "F.Adhes" user "F.Adhesive")
		(11 "B.Adhes" user "B.Adhesive")
		(13 "F.Paste" user "Package Geometry/Pastemask Top")
		(15 "B.Paste" user "Package Geometry/Pastemask Bottom")
		(5 "F.SilkS" user "Ref Des/Silkscreen Top")
		(7 "B.SilkS" user "Ref Des/Silkscreen Bottom")
		(1 "F.Mask" user "Board Geometry/Soldermask Top")
		(3 "B.Mask" user "Board Geometry/Soldermask Bottom")
		(17 "Dwgs.User" user "User.Drawings")
		(19 "Cmts.User" user "User.Comments")
		(21 "Eco1.User" user "User.Eco1")
		(23 "Eco2.User" user "User.Eco2")
		(25 "Edge.Cuts" user "Board Geometry/Outline")
		(27 "Margin" user)
		(31 "F.CrtYd" user "Package Geometry/Place Bound Top")
		(29 "B.CrtYd" user "Package Geometry/Place Bound Bottom")
		(35 "F.Fab" user "Ref Des/Assembly Top")
		(33 "B.Fab" user "Ref Des/Assembly Bottom")
	)
	(footprint ""
		(layer "F.Cu")
		(at 290.908994 -26.03373)
		(property "Reference" "R4072"
			(at 0 0 0)
			(layer "F.SilkS")
			(hide yes)
			(effects
				(font
					(size 1.27 1.27)
				)
			)
		)
		(property "Value" ""
			(at 0 0 0)
			(layer "F.Fab")
			(effects
				(font
					(size 1.27 1.27)
				)
			)
		)
		(duplicate_pad_numbers_are_jumpers no)
		(fp_line
			(start -0.7874 -0.4064)
			(end 0.7874 -0.4064)
			(stroke
				(width 0.1524)
				(type default)
			)
			(layer "F.SilkS")
		)
		(fp_line
			(start -0.7874 0.4064)
			(end -0.7874 -0.4064)
			(stroke
				(width 0.1524)
				(type default)
			)
			(layer "F.SilkS")
		)
		(fp_line
			(start 0.7874 -0.4064)
			(end 0.7874 0.4064)
			(stroke
				(width 0.1524)
				(type default)
			)
			(layer "F.SilkS")
		)
		(fp_line
			(start 0.7874 0.4064)
			(end -0.7874 0.4064)
			(stroke
				(width 0.1524)
				(type default)
			)
			(layer "F.SilkS")
		)
		(fp_line
			(start -0.67945 -0.305054)
			(end -0.12065 -0.305054)
			(stroke
				(width 0.1)
				(type default)
			)
			(layer "F.Fab")
		)
		(fp_line
			(start -0.67945 0.3048)
			(end -0.67945 -0.305054)
			(stroke
				(width 0.1)
				(type default)
			)
			(layer "F.Fab")
		)
		(fp_line
			(start -0.12065 -0.305054)
			(end -0.12065 -0.2794)
			(stroke
				(width 0.1)
				(type default)
			)
			(layer "F.Fab")
		)
		(fp_line
			(start -0.12065 -0.2794)
			(end 0.12065 -0.2794)
			(stroke
				(width 0.1)
				(type default)
			)
			(layer "F.Fab")
		)
		(fp_line
			(start -0.12065 0.2794)
			(end -0.12065 0.3048)
			(stroke
				(width 0.1)
				(type default)
			)
			(layer "F.Fab")
		)
		(fp_line
			(start -0.12065 0.3048)
			(end -0.67945 0.3048)
			(stroke
				(width 0.1)
				(type default)
			)
			(layer "F.Fab")
		)
		(fp_line
			(start 0.120396 0.2794)
			(end -0.12065 0.2794)
			(stroke
				(width 0.1)
				(type default)
			)
			(layer "F.Fab")
		)
		(fp_line
			(start 0.120396 0.3048)
			(end 0.120396 0.2794)
			(stroke
				(width 0.1)
				(type default)
			)
			(layer "F.Fab")
		)
		(fp_line
			(start 0.12065 -0.3048)
			(end 0.67945 -0.3048)
			(stroke
				(width 0.1)
				(type default)
			)
			(layer "F.Fab")
		)
		(fp_line
			(start 0.12065 -0.2794)
			(end 0.12065 -0.3048)
			(stroke
				(width 0.1)
				(type default)
			)
			(layer "F.Fab")
		)
		(fp_line
			(start 0.67945 -0.3048)
			(end 0.67945 0.3048)
			(stroke
				(width 0.1)
				(type default)
			)
			(layer "F.Fab")
		)
		(fp_line
			(start 0.67945 0.3048)
			(end 0.120396 0.3048)
			(stroke
				(width 0.1)
				(type default)
			)
			(layer "F.Fab")
		)
		(pad "1" smd circle
			(at -0.40005 0)
			(size 0 0)
			(layers "F.Cu" "F.Mask" "F.Paste")
			(net "P3V3_AUX")
		)
		(pad "2" smd circle
			(at 0.40005 0)
			(size 0 0)
			(layers "F.Cu" "F.Mask" "F.Paste")
			(net "PRSNT_SSD10_R_N")
		)
	)
	(footprint ""
		(layer "F.Cu")
		(at 95.105728 -244.808248 180)
		(property "Reference" "R814"
			(at 0 0 180)
			(layer "F.SilkS")
			(hide yes)
			(effects
				(font
					(size 1.27 1.27)
				)
			)
		)
		(property "Value" ""
			(at 0 0 180)
			(layer "F.Fab")
			(effects
				(font
					(size 1.27 1.27)
				)
			)
		)
		(duplicate_pad_numbers_are_jumpers no)
		(fp_line
			(start 0.7874 0.4064)
			(end -0.7874 0.4064)
			(stroke
				(width 0.1524)
				(type default)
			)
			(layer "F.SilkS")
		)
		(fp_line
			(start 0.7874 -0.4064)
			(end 0.7874 0.4064)
			(stroke
				(width 0.1524)
				(type default)
			)
			(layer "F.SilkS")
		)
		(fp_line
			(start -0.7874 0.4064)
			(end -0.7874 -0.4064)
			(stroke
				(width 0.1524)
				(type default)
			)
			(layer "F.SilkS")
		)
		(fp_line
			(start -0.7874 -0.4064)
			(end 0.7874 -0.4064)
			(stroke
				(width 0.1524)
				(type default)
			)
			(layer "F.SilkS")
		)
		(fp_line
			(start 0.67945 0.3048)
			(end 0.120396 0.3048)
			(stroke
				(width 0.1)
				(type default)
			)
			(layer "F.Fab")
		)
		(fp_line
			(start 0.67945 -0.3048)
			(end 0.67945 0.3048)
			(stroke
				(width 0.1)
				(type default)
			)
			(layer "F.Fab")
		)
		(fp_line
			(start 0.12065 -0.2794)
			(end 0.12065 -0.3048)
			(stroke
				(width 0.1)
				(type default)
			)
			(layer "F.Fab")
		)
		(fp_line
			(start 0.12065 -0.3048)
			(end 0.67945 -0.3048)
			(stroke
				(width 0.1)
				(type default)
			)
			(layer "F.Fab")
		)
		(fp_line
			(start 0.120396 0.3048)
			(end 0.120396 0.2794)
			(stroke
				(width 0.1)
				(type default)
			)
			(layer "F.Fab")
		)
		(fp_line
			(start 0.120396 0.2794)
			(end -0.12065 0.2794)
			(stroke
				(width 0.1)
				(type default)
			)
			(layer "F.Fab")
		)
		(fp_line
			(start -0.12065 0.3048)
			(end -0.67945 0.3048)
			(stroke
				(width 0.1)
				(type default)
			)
			(layer "F.Fab")
		)
		(fp_line
			(start -0.12065 0.2794)
			(end -0.12065 0.3048)
			(stroke
				(width 0.1)
				(type default)
			)
			(layer "F.Fab")
		)
		(fp_line
			(start -0.12065 -0.2794)
			(end 0.12065 -0.2794)
			(stroke
				(width 0.1)
				(type default)
			)
			(layer "F.Fab")
		)
		(fp_line
			(start -0.12065 -0.305054)
			(end -0.12065 -0.2794)
			(stroke
				(width 0.1)
				(type default)
			)
			(layer "F.Fab")
		)
		(fp_line
			(start -0.67945 0.3048)
			(end -0.67945 -0.305054)
			(stroke
				(width 0.1)
				(type default)
			)
			(layer "F.Fab")
		)
		(fp_line
			(start -0.67945 -0.305054)
			(end -0.12065 -0.305054)
			(stroke
				(width 0.1)
				(type default)
			)
			(layer "F.Fab")
		)
		(pad "1" smd circle
			(at -0.40005 0 180)
			(size 0 0)
			(layers "F.Cu" "F.Mask" "F.Paste")
			(net "PEX_P1V8_ADC_A0")
		)
		(pad "2" smd circle
			(at 0.40005 0 180)
			(size 0 0)
			(layers "F.Cu" "F.Mask" "F.Paste")
			(net "P3V3_AUX")
		)
	)
	(footprint ""
		(layer "F.Cu")
		(at 269.385542 -115.2652 90)
		(property "Reference" "R248"
			(at 0 0 90)
			(layer "F.SilkS")
			(hide yes)
			(effects
				(font
					(size 1.27 1.27)
				)
			)
		)
		(property "Value" ""
			(at 0 0 90)
			(layer "F.Fab")
			(effects
				(font
					(size 1.27 1.27)
				)
			)
		)
		(duplicate_pad_numbers_are_jumpers no)
		(fp_line
			(start 0.7874 -0.4064)
			(end 0.7874 0.4064)
			(stroke
				(width 0.1524)
				(type default)
			)
			(layer "F.SilkS")
		)
		(fp_line
			(start -0.7874 -0.4064)
			(end 0.7874 -0.4064)
			(stroke
				(width 0.1524)
				(type default)
			)
			(layer "F.SilkS")
		)
		(fp_line
			(start 0.7874 0.4064)
			(end -0.7874 0.4064)
			(stroke
				(width 0.1524)
				(type default)
			)
			(layer "F.SilkS")
		)
		(fp_line
			(start -0.7874 0.4064)
			(end -0.7874 -0.4064)
			(stroke
				(width 0.1524)
				(type default)
			)
			(layer "F.SilkS")
		)
		(fp_line
			(start -0.12065 -0.305054)
			(end -0.12065 -0.2794)
			(stroke
				(width 0.1)
				(type default)
			)
			(layer "F.Fab")
		)
		(fp_line
			(start -0.67945 -0.305054)
			(end -0.12065 -0.305054)
			(stroke
				(width 0.1)
				(type default)
			)
			(layer "F.Fab")
		)
		(fp_line
			(start 0.67945 -0.3048)
			(end 0.67945 0.3048)
			(stroke
				(width 0.1)
				(type default)
			)
			(layer "F.Fab")
		)
		(fp_line
			(start 0.12065 -0.3048)
			(end 0.67945 -0.3048)
			(stroke
				(width 0.1)
				(type default)
			)
			(layer "F.Fab")
		)
		(fp_line
			(start 0.12065 -0.2794)
			(end 0.12065 -0.3048)
			(stroke
				(width 0.1)
				(type default)
			)
			(layer "F.Fab")
		)
		(fp_line
			(start -0.12065 -0.2794)
			(end 0.12065 -0.2794)
			(stroke
				(width 0.1)
				(type default)
			)
			(layer "F.Fab")
		)
		(fp_line
			(start 0.120396 0.2794)
			(end -0.12065 0.2794)
			(stroke
				(width 0.1)
				(type default)
			)
			(layer "F.Fab")
		)
		(fp_line
			(start -0.12065 0.2794)
			(end -0.12065 0.3048)
			(stroke
				(width 0.1)
				(type default)
			)
			(layer "F.Fab")
		)
		(fp_line
			(start 0.67945 0.3048)
			(end 0.120396 0.3048)
			(stroke
				(width 0.1)
				(type default)
			)
			(layer "F.Fab")
		)
		(fp_line
			(start 0.120396 0.3048)
			(end 0.120396 0.2794)
			(stroke
				(width 0.1)
				(type default)
			)
			(layer "F.Fab")
		)
		(fp_line
			(start -0.12065 0.3048)
			(end -0.67945 0.3048)
			(stroke
				(width 0.1)
				(type default)
			)
			(layer "F.Fab")
		)
		(fp_line
			(start -0.67945 0.3048)
			(end -0.67945 -0.305054)
			(stroke
				(width 0.1)
				(type default)
			)
			(layer "F.Fab")
		)
		(pad "1" smd circle
			(at -0.40005 0 90)
			(size 0 0)
			(layers "F.Cu" "F.Mask" "F.Paste")
			(net "P3V3_AUX")
		)
		(pad "2" smd circle
			(at 0.40005 0 90)
			(size 0 0)
			(layers "F.Cu" "F.Mask" "F.Paste")
			(net "HP_NIC4_EN")
		)
	)
	(footprint ""
		(layer "F.Cu")
		(at 138.985244 -94.671642 180)
		(property "Reference" "R1571"
			(at 0 0 180)
			(layer "F.SilkS")
			(hide yes)
			(effects
				(font
					(size 1.27 1.27)
				)
			)
		)
		(property "Value" ""
			(at 0 0 180)
			(layer "F.Fab")
			(effects
				(font
					(size 1.27 1.27)
				)
			)
		)
		(duplicate_pad_numbers_are_jumpers no)
		(fp_line
			(start 0.7874 0.4064)
			(end -0.7874 0.4064)
			(stroke
				(width 0.1524)
				(type default)
			)
			(layer "F.SilkS")
		)
		(fp_line
			(start 0.7874 -0.4064)
			(end 0.7874 0.4064)
			(stroke
				(width 0.1524)
				(type default)
			)
			(layer "F.SilkS")
		)
		(fp_line
			(start -0.7874 0.4064)
			(end -0.7874 -0.4064)
			(stroke
				(width 0.1524)
				(type default)
			)
			(layer "F.SilkS")
		)
		(fp_line
			(start -0.7874 -0.4064)
			(end 0.7874 -0.4064)
			(stroke
				(width 0.1524)
				(type default)
			)
			(layer "F.SilkS")
		)
		(fp_line
			(start 0.67945 0.3048)
			(end 0.120396 0.3048)
			(stroke
				(width 0.1)
				(type default)
			)
			(layer "F.Fab")
		)
		(fp_line
			(start 0.67945 -0.3048)
			(end 0.67945 0.3048)
			(stroke
				(width 0.1)
				(type default)
			)
			(layer "F.Fab")
		)
		(fp_line
			(start 0.12065 -0.2794)
			(end 0.12065 -0.3048)
			(stroke
				(width 0.1)
				(type default)
			)
			(layer "F.Fab")
		)
		(fp_line
			(start 0.12065 -0.3048)
			(end 0.67945 -0.3048)
			(stroke
				(width 0.1)
				(type default)
			)
			(layer "F.Fab")
		)
		(fp_line
			(start 0.120396 0.3048)
			(end 0.120396 0.2794)
			(stroke
				(width 0.1)
				(type default)
			)
			(layer "F.Fab")
		)
		(fp_line
			(start 0.120396 0.2794)
			(end -0.12065 0.2794)
			(stroke
				(width 0.1)
				(type default)
			)
			(layer "F.Fab")
		)
		(fp_line
			(start -0.12065 0.3048)
			(end -0.67945 0.3048)
			(stroke
				(width 0.1)
				(type default)
			)
			(layer "F.Fab")
		)
		(fp_line
			(start -0.12065 0.2794)
			(end -0.12065 0.3048)
			(stroke
				(width 0.1)
				(type default)
			)
			(layer "F.Fab")
		)
		(fp_line
			(start -0.12065 -0.2794)
			(end 0.12065 -0.2794)
			(stroke
				(width 0.1)
				(type default)
			)
			(layer "F.Fab")
		)
		(fp_line
			(start -0.12065 -0.305054)
			(end -0.12065 -0.2794)
			(stroke
				(width 0.1)
				(type default)
			)
			(layer "F.Fab")
		)
		(fp_line
			(start -0.67945 0.3048)
			(end -0.67945 -0.305054)
			(stroke
				(width 0.1)
				(type default)
			)
			(layer "F.Fab")
		)
		(fp_line
			(start -0.67945 -0.305054)
			(end -0.12065 -0.305054)
			(stroke
				(width 0.1)
				(type default)
			)
			(layer "F.Fab")
		)
		(pad "1" smd circle
			(at -0.40005 0 180)
			(size 0 0)
			(layers "F.Cu" "F.Mask" "F.Paste")
			(net "P3V3_AUX")
		)
		(pad "2" smd circle
			(at 0.40005 0 180)
			(size 0 0)
			(layers "F.Cu" "F.Mask" "F.Paste")
			(net "SMB_BIC_I2C9_MUX0_SSD7_R_SDA")
		)
	)
	(footprint ""
		(layer "F.Cu")
		(at 31.742888 -343.952322 90)
		(property "Reference" "C2162"
			(at 0 0 90)
			(layer "F.SilkS")
			(hide yes)
			(effects
				(font
					(size 1.27 1.27)
				)
			)
		)
		(property "Value" ""
			(at 0 0 90)
			(layer "F.Fab")
			(effects
				(font
					(size 1.27 1.27)
				)
			)
		)
		(duplicate_pad_numbers_are_jumpers no)
		(fp_line
			(start 0.299974 -0.150114)
			(end 0.299974 0.150114)
			(stroke
				(width 0.1)
				(type default)
			)
			(layer "F.Fab")
		)
		(fp_line
			(start -0.299974 -0.150114)
			(end 0.299974 -0.150114)
			(stroke
				(width 0.1)
				(type default)
			)
			(layer "F.Fab")
		)
		(fp_line
			(start 0.299974 0.150114)
			(end -0.299974 0.150114)
			(stroke
				(width 0.1)
				(type default)
			)
			(layer "F.Fab")
		)
		(fp_line
			(start -0.299974 0.150114)
			(end -0.299974 -0.150114)
			(stroke
				(width 0.1)
				(type default)
			)
			(layer "F.Fab")
		)
		(pad "1" smd rect
			(at -0.2667 0 90)
			(size 0.3048 0.381)
			(layers "F.Cu" "F.Mask" "F.Paste")
			(net "P5E_PEX0_STN4_TX_DP<74>")
		)
		(pad "2" smd rect
			(at 0.2667 0 90)
			(size 0.3048 0.381)
			(layers "F.Cu" "F.Mask" "F.Paste")
			(net "P5E_PEX0_STN4_TX_C_DP<74>")
		)
	)
	(footprint ""
		(layer "F.Cu")
		(at 78.320392 -458.963014)
		(property "Reference" "X8"
			(at -0.1778 -1.92913 0)
			(unlocked yes)
			(layer "F.SilkS")
			(effects
				(font
					(size 0.7874 0.5842)
					(thickness 0.1524)
				)
				(justify left)
			)
		)
		(property "Value" ""
			(at 0 0 0)
			(layer "F.Fab")
			(effects
				(font
					(size 1.27 1.27)
				)
			)
		)
		(property "Device Type" "TP_TDR_4P_FTS_MPKT4_H025P0200_IO_TP15_TP_TDR_4P_DIP"
			(at 1.30175 1.27 90)
			(unlocked yes)
			(layer "F.Fab")
			(hide yes)
			(effects
				(font
					(size 0.635 0.4064)
					(thickness 0.1524)
				)
			)
		)
		(property "User Part Number" "TP15"
			(at 1.30175 1.27 90)
			(unlocked yes)
			(layer "Cmts.User")
			(hide yes)
			(effects
				(font
					(size 0.635 0.4064)
					(thickness 0.1524)
				)
			)
		)
		(duplicate_pad_numbers_are_jumpers no)
		(fp_line
			(start 0 -1.27)
			(end 0 -0.635)
			(stroke
				(width 0.1524)
				(type default)
			)
			(layer "F.SilkS")
		)
		(fp_line
			(start 0 0.635)
			(end 0 1.905)
			(stroke
				(width 0.1524)
				(type default)
			)
			(layer "F.SilkS")
		)
		(fp_line
			(start 0 3.175)
			(end 0 3.81)
			(stroke
				(width 0.1524)
				(type default)
			)
			(layer "F.SilkS")
		)
		(fp_line
			(start 0 3.81)
			(end 2.54 3.81)
			(stroke
				(width 0.1524)
				(type default)
			)
			(layer "F.SilkS")
		)
		(fp_line
			(start 2.54 -1.27)
			(end 0 -1.27)
			(stroke
				(width 0.1524)
				(type default)
			)
			(layer "F.SilkS")
		)
		(fp_line
			(start 2.54 -1.1303)
			(end 2.54 -1.27)
			(stroke
				(width 0.1524)
				(type default)
			)
			(layer "F.SilkS")
		)
		(fp_line
			(start 2.54 1.4097)
			(end 2.54 1.1303)
			(stroke
				(width 0.1524)
				(type default)
			)
			(layer "F.SilkS")
		)
		(fp_line
			(start 2.54 3.81)
			(end 2.54 3.6703)
			(stroke
				(width 0.1524)
				(type default)
			)
			(layer "F.SilkS")
		)
		(fp_poly
			(pts
				(xy -0.761746 0) (xy -2.285746 -0.762) (xy -2.285746 0.762)
			)
			(stroke
				(width 0)
				(type default)
			)
			(fill yes)
			(layer "F.SilkS")
		)
		(fp_line
			(start 0 -1.27)
			(end 0 3.81)
			(stroke
				(width 0.1)
				(type default)
			)
			(layer "F.Fab")
		)
		(fp_line
			(start 0 3.81)
			(end 2.54 3.81)
			(stroke
				(width 0.1)
				(type default)
			)
			(layer "F.Fab")
		)
		(fp_line
			(start 2.54 -1.27)
			(end 0 -1.27)
			(stroke
				(width 0.1)
				(type default)
			)
			(layer "F.Fab")
		)
		(fp_line
			(start 2.54 3.81)
			(end 2.54 -1.27)
			(stroke
				(width 0.1)
				(type default)
			)
			(layer "F.Fab")
		)
		(fp_poly
			(pts
				(xy -0.761746 0) (xy -2.285746 -0.762) (xy -2.285746 0.762)
			)
			(stroke
				(width 0)
				(type default)
			)
			(fill yes)
			(layer "F.Fab")
		)
		(pad "1" thru_hole circle
			(at 0 0)
			(size 1.0033 1.0033)
			(drill 0.249936)
			(layers "*.Cu" "*.Mask")
			(remove_unused_layers no)
			(net "TDR_DIFF_85_IN1_DIP")
			(clearance 0.10795)
			(thermal_gap 0.10795)
			(padstack
				(mode front_inner_back)
				(layer "Inner"
					(shape circle)
					(size 0.8001 0.8001)
					(clearance 0.1524)
				)
				(layer "B.Cu"
					(shape circle)
					(size 1.0033 1.0033)
					(clearance 0.10795)
				)
			)
		)
		(pad "2" thru_hole circle
			(at 2.54 0)
			(size 1.9939 1.9939)
			(drill 0.249936)
			(layers "*.Cu" "*.Mask")
			(remove_unused_layers no)
			(net "COUPON_GND1")
			(clearance 0.10795)
			(thermal_gap 0.10795)
			(padstack
				(mode front_inner_back)
				(layer "Inner"
					(shape circle)
					(size 0.8001 0.8001)
					(clearance 0.1524)
				)
				(layer "B.Cu"
					(shape circle)
					(size 1.9939 1.9939)
					(clearance 0.10795)
				)
			)
		)
		(pad "3" thru_hole circle
			(at 2.54 2.54)
			(size 1.9939 1.9939)
			(drill 0.249936)
			(layers "*.Cu" "*.Mask")
			(remove_unused_layers no)
			(net "COUPON_GND1")
			(clearance 0.10795)
			(thermal_gap 0.10795)
			(padstack
				(mode front_inner_back)
				(layer "Inner"
					(shape circle)
					(size 0.8001 0.8001)
					(clearance 0.1524)
				)
				(layer "B.Cu"
					(shape circle)
					(size 1.9939 1.9939)
					(clearance 0.10795)
				)
			)
		)
		(pad "4" thru_hole circle
			(at 0 2.54)
			(size 1.0033 1.0033)
			(drill 0.249936)
			(layers "*.Cu" "*.Mask")
			(remove_unused_layers no)
			(net "TDR_DIFF_85_IN1_DIN")
			(clearance 0.10795)
			(thermal_gap 0.10795)
			(padstack
				(mode front_inner_back)
				(layer "Inner"
					(shape circle)
					(size 0.8001 0.8001)
					(clearance 0.1524)
				)
				(layer "B.Cu"
					(shape circle)
					(size 1.0033 1.0033)
					(clearance 0.10795)
				)
			)
		)
	)
)
